(kicad_pcb
	(version 20260206)
	(generator "pcbnew")
	(generator_version "10.0")
	(general
		(thickness 1.6)
		(legacy_teardrops no)
	)
	(paper "A4")
	(title_block
		(title "01162023_DA0F0TEBIF0_F0T_Expander_BD_F_brd_V02_OCP.brd")
		(comment 1 "Grand Teton / footprints 4500-4507 of 9728")
	)
	(layers
		(0 "F.Cu" signal "TOP")
		(4 "In1.Cu" signal "GND")
		(6 "In2.Cu" signal "VCC")
		(8 "In3.Cu" signal "VCC1")
		(10 "In4.Cu" signal "GND1")
		(12 "In5.Cu" signal "IN1")
		(14 "In6.Cu" signal "GND2")
		(16 "In7.Cu" signal "IN2")
		(18 "In8.Cu" signal "GND3")
		(20 "In9.Cu" signal "IN3")
		(22 "In10.Cu" signal "GND4")
		(24 "In11.Cu" signal "IN4")
		(26 "In12.Cu" signal "GND5")
		(28 "In13.Cu" signal "IN5")
		(30 "In14.Cu" signal "GND6")
		(32 "In15.Cu" signal "IN6")
		(34 "In16.Cu" signal "GND7")
		(2 "B.Cu" signal "BOTTOM")
		(9 "F.Adhes" user "F.Adhesive")
		(11 "B.Adhes" user "B.Adhesive")
		(13 "F.Paste" user "Package Geometry/Pastemask Top")
		(15 "B.Paste" user "Package Geometry/Pastemask Bottom")
		(5 "F.SilkS" user "Ref Des/Silkscreen Top")
		(7 "B.SilkS" user "Ref Des/Silkscreen Bottom")
		(1 "F.Mask" user "Board Geometry/Soldermask Top")
		(3 "B.Mask" user "Board Geometry/Soldermask Bottom")
		(17 "Dwgs.User" user "User.Drawings")
		(19 "Cmts.User" user "User.Comments")
		(21 "Eco1.User" user "User.Eco1")
		(23 "Eco2.User" user "User.Eco2")
		(25 "Edge.Cuts" user "Board Geometry/Outline")
		(27 "Margin" user)
		(31 "F.CrtYd" user "Package Geometry/Place Bound Top")
		(29 "B.CrtYd" user "Package Geometry/Place Bound Bottom")
		(35 "F.Fab" user "Ref Des/Assembly Top")
		(33 "B.Fab" user "Ref Des/Assembly Bottom")
	)
	(footprint ""
		(layer "F.Cu")
		(at 446.734438 -30.94609 180)
		(property "Reference" "C726"
			(at 0 0 180)
			(layer "F.SilkS")
			(hide yes)
			(effects
				(font
					(size 1.27 1.27)
				)
			)
		)
		(property "Value" ""
			(at 0 0 180)
			(layer "F.Fab")
			(effects
				(font
					(size 1.27 1.27)
				)
			)
		)
		(duplicate_pad_numbers_are_jumpers no)
		(fp_line
			(start 0.299974 0.150114)
			(end -0.299974 0.150114)
			(stroke
				(width 0.1)
				(type default)
			)
			(layer "F.Fab")
		)
		(fp_line
			(start 0.299974 -0.150114)
			(end 0.299974 0.150114)
			(stroke
				(width 0.1)
				(type default)
			)
			(layer "F.Fab")
		)
		(fp_line
			(start -0.299974 0.150114)
			(end -0.299974 -0.150114)
			(stroke
				(width 0.1)
				(type default)
			)
			(layer "F.Fab")
		)
		(fp_line
			(start -0.299974 -0.150114)
			(end 0.299974 -0.150114)
			(stroke
				(width 0.1)
				(type default)
			)
			(layer "F.Fab")
		)
		(pad "1" smd rect
			(at -0.2667 0 180)
			(size 0.3048 0.381)
			(layers "F.Cu" "F.Mask" "F.Paste")
			(net "P5E_PEX3_STN2_TX_DP<33>")
		)
		(pad "2" smd rect
			(at 0.2667 0 180)
			(size 0.3048 0.381)
			(layers "F.Cu" "F.Mask" "F.Paste")
			(net "P5E_PEX3_STN2_TX_C_DP<33>")
		)
	)
	(footprint ""
		(layer "F.Cu")
		(at 278.443182 -402.338032 -90)
		(property "Reference" "C2704"
			(at 0 0 270)
			(layer "F.SilkS")
			(hide yes)
			(effects
				(font
					(size 1.27 1.27)
				)
			)
		)
		(property "Value" ""
			(at 0 0 270)
			(layer "F.Fab")
			(effects
				(font
					(size 1.27 1.27)
				)
			)
		)
		(duplicate_pad_numbers_are_jumpers no)
		(fp_line
			(start -0.7874 0.4064)
			(end -0.7874 -0.4064)
			(stroke
				(width 0.1524)
				(type default)
			)
			(layer "F.SilkS")
		)
		(fp_line
			(start 0.7874 0.4064)
			(end -0.7874 0.4064)
			(stroke
				(width 0.1524)
				(type default)
			)
			(layer "F.SilkS")
		)
		(fp_line
			(start -0.7874 -0.4064)
			(end 0.7874 -0.4064)
			(stroke
				(width 0.1524)
				(type default)
			)
			(layer "F.SilkS")
		)
		(fp_line
			(start 0.7874 -0.4064)
			(end 0.7874 0.4064)
			(stroke
				(width 0.1524)
				(type default)
			)
			(layer "F.SilkS")
		)
		(fp_line
			(start -0.67945 0.3048)
			(end -0.67945 -0.305054)
			(stroke
				(width 0.1)
				(type default)
			)
			(layer "F.Fab")
		)
		(fp_line
			(start -0.12065 0.3048)
			(end -0.67945 0.3048)
			(stroke
				(width 0.1)
				(type default)
			)
			(layer "F.Fab")
		)
		(fp_line
			(start 0.120396 0.3048)
			(end 0.120396 0.2794)
			(stroke
				(width 0.1)
				(type default)
			)
			(layer "F.Fab")
		)
		(fp_line
			(start 0.67945 0.3048)
			(end 0.120396 0.3048)
			(stroke
				(width 0.1)
				(type default)
			)
			(layer "F.Fab")
		)
		(fp_line
			(start -0.12065 0.2794)
			(end -0.12065 0.3048)
			(stroke
				(width 0.1)
				(type default)
			)
			(layer "F.Fab")
		)
		(fp_line
			(start 0.120396 0.2794)
			(end -0.12065 0.2794)
			(stroke
				(width 0.1)
				(type default)
			)
			(layer "F.Fab")
		)
		(fp_line
			(start -0.12065 -0.2794)
			(end 0.12065 -0.2794)
			(stroke
				(width 0.1)
				(type default)
			)
			(layer "F.Fab")
		)
		(fp_line
			(start 0.12065 -0.2794)
			(end 0.12065 -0.3048)
			(stroke
				(width 0.1)
				(type default)
			)
			(layer "F.Fab")
		)
		(fp_line
			(start 0.12065 -0.3048)
			(end 0.67945 -0.3048)
			(stroke
				(width 0.1)
				(type default)
			)
			(layer "F.Fab")
		)
		(fp_line
			(start 0.67945 -0.3048)
			(end 0.67945 0.3048)
			(stroke
				(width 0.1)
				(type default)
			)
			(layer "F.Fab")
		)
		(fp_line
			(start -0.67945 -0.305054)
			(end -0.12065 -0.305054)
			(stroke
				(width 0.1)
				(type default)
			)
			(layer "F.Fab")
		)
		(fp_line
			(start -0.12065 -0.305054)
			(end -0.12065 -0.2794)
			(stroke
				(width 0.1)
				(type default)
			)
			(layer "F.Fab")
		)
		(pad "1" smd circle
			(at -0.40005 0 270)
			(size 0 0)
			(layers "F.Cu" "F.Mask" "F.Paste")
			(net "GND")
		)
		(pad "2" smd circle
			(at 0.40005 0 270)
			(size 0 0)
			(layers "F.Cu" "F.Mask" "F.Paste")
			(net "P3V3_AUX")
		)
	)
	(footprint ""
		(layer "F.Cu")
		(at 454.251822 -108.054902 180)
		(property "Reference" "PC821"
			(at 0 0 180)
			(layer "F.SilkS")
			(hide yes)
			(effects
				(font
					(size 1.27 1.27)
				)
			)
		)
		(property "Value" ""
			(at 0 0 180)
			(layer "F.Fab")
			(effects
				(font
					(size 1.27 1.27)
				)
			)
		)
		(duplicate_pad_numbers_are_jumpers no)
		(fp_line
			(start 0.7874 0.4064)
			(end -0.7874 0.4064)
			(stroke
				(width 0.1524)
				(type default)
			)
			(layer "F.SilkS")
		)
		(fp_line
			(start 0.7874 -0.4064)
			(end 0.7874 0.4064)
			(stroke
				(width 0.1524)
				(type default)
			)
			(layer "F.SilkS")
		)
		(fp_line
			(start -0.7874 0.4064)
			(end -0.7874 -0.4064)
			(stroke
				(width 0.1524)
				(type default)
			)
			(layer "F.SilkS")
		)
		(fp_line
			(start -0.7874 -0.4064)
			(end 0.7874 -0.4064)
			(stroke
				(width 0.1524)
				(type default)
			)
			(layer "F.SilkS")
		)
		(fp_line
			(start 0.67945 0.3048)
			(end 0.120396 0.3048)
			(stroke
				(width 0.1)
				(type default)
			)
			(layer "F.Fab")
		)
		(fp_line
			(start 0.67945 -0.3048)
			(end 0.67945 0.3048)
			(stroke
				(width 0.1)
				(type default)
			)
			(layer "F.Fab")
		)
		(fp_line
			(start 0.12065 -0.2794)
			(end 0.12065 -0.3048)
			(stroke
				(width 0.1)
				(type default)
			)
			(layer "F.Fab")
		)
		(fp_line
			(start 0.12065 -0.3048)
			(end 0.67945 -0.3048)
			(stroke
				(width 0.1)
				(type default)
			)
			(layer "F.Fab")
		)
		(fp_line
			(start 0.120396 0.3048)
			(end 0.120396 0.2794)
			(stroke
				(width 0.1)
				(type default)
			)
			(layer "F.Fab")
		)
		(fp_line
			(start 0.120396 0.2794)
			(end -0.12065 0.2794)
			(stroke
				(width 0.1)
				(type default)
			)
			(layer "F.Fab")
		)
		(fp_line
			(start -0.12065 0.3048)
			(end -0.67945 0.3048)
			(stroke
				(width 0.1)
				(type default)
			)
			(layer "F.Fab")
		)
		(fp_line
			(start -0.12065 0.2794)
			(end -0.12065 0.3048)
			(stroke
				(width 0.1)
				(type default)
			)
			(layer "F.Fab")
		)
		(fp_line
			(start -0.12065 -0.2794)
			(end 0.12065 -0.2794)
			(stroke
				(width 0.1)
				(type default)
			)
			(layer "F.Fab")
		)
		(fp_line
			(start -0.12065 -0.305054)
			(end -0.12065 -0.2794)
			(stroke
				(width 0.1)
				(type default)
			)
			(layer "F.Fab")
		)
		(fp_line
			(start -0.67945 0.3048)
			(end -0.67945 -0.305054)
			(stroke
				(width 0.1)
				(type default)
			)
			(layer "F.Fab")
		)
		(fp_line
			(start -0.67945 -0.305054)
			(end -0.12065 -0.305054)
			(stroke
				(width 0.1)
				(type default)
			)
			(layer "F.Fab")
		)
		(pad "1" smd circle
			(at -0.40005 0 180)
			(size 0 0)
			(layers "F.Cu" "F.Mask" "F.Paste")
			(net "P12V_AUX")
		)
		(pad "2" smd circle
			(at 0.40005 0 180)
			(size 0 0)
			(layers "F.Cu" "F.Mask" "F.Paste")
			(net "GND")
		)
	)
	(footprint ""
		(layer "F.Cu")
		(at 224.845626 -368.976402 180)
		(property "Reference" "PR13"
			(at 0 0 180)
			(layer "F.SilkS")
			(hide yes)
			(effects
				(font
					(size 1.27 1.27)
				)
			)
		)
		(property "Value" ""
			(at 0 0 180)
			(layer "F.Fab")
			(effects
				(font
					(size 1.27 1.27)
				)
			)
		)
		(duplicate_pad_numbers_are_jumpers no)
		(fp_line
			(start 0.7874 0.4064)
			(end -0.7874 0.4064)
			(stroke
				(width 0.1524)
				(type default)
			)
			(layer "F.SilkS")
		)
		(fp_line
			(start 0.7874 -0.4064)
			(end 0.7874 0.4064)
			(stroke
				(width 0.1524)
				(type default)
			)
			(layer "F.SilkS")
		)
		(fp_line
			(start -0.7874 0.4064)
			(end -0.7874 -0.4064)
			(stroke
				(width 0.1524)
				(type default)
			)
			(layer "F.SilkS")
		)
		(fp_line
			(start -0.7874 -0.4064)
			(end 0.7874 -0.4064)
			(stroke
				(width 0.1524)
				(type default)
			)
			(layer "F.SilkS")
		)
		(fp_line
			(start 0.67945 0.3048)
			(end 0.120396 0.3048)
			(stroke
				(width 0.1)
				(type default)
			)
			(layer "F.Fab")
		)
		(fp_line
			(start 0.67945 -0.3048)
			(end 0.67945 0.3048)
			(stroke
				(width 0.1)
				(type default)
			)
			(layer "F.Fab")
		)
		(fp_line
			(start 0.12065 -0.2794)
			(end 0.12065 -0.3048)
			(stroke
				(width 0.1)
				(type default)
			)
			(layer "F.Fab")
		)
		(fp_line
			(start 0.12065 -0.3048)
			(end 0.67945 -0.3048)
			(stroke
				(width 0.1)
				(type default)
			)
			(layer "F.Fab")
		)
		(fp_line
			(start 0.120396 0.3048)
			(end 0.120396 0.2794)
			(stroke
				(width 0.1)
				(type default)
			)
			(layer "F.Fab")
		)
		(fp_line
			(start 0.120396 0.2794)
			(end -0.12065 0.2794)
			(stroke
				(width 0.1)
				(type default)
			)
			(layer "F.Fab")
		)
		(fp_line
			(start -0.12065 0.3048)
			(end -0.67945 0.3048)
			(stroke
				(width 0.1)
				(type default)
			)
			(layer "F.Fab")
		)
		(fp_line
			(start -0.12065 0.2794)
			(end -0.12065 0.3048)
			(stroke
				(width 0.1)
				(type default)
			)
			(layer "F.Fab")
		)
		(fp_line
			(start -0.12065 -0.2794)
			(end 0.12065 -0.2794)
			(stroke
				(width 0.1)
				(type default)
			)
			(layer "F.Fab")
		)
		(fp_line
			(start -0.12065 -0.305054)
			(end -0.12065 -0.2794)
			(stroke
				(width 0.1)
				(type default)
			)
			(layer "F.Fab")
		)
		(fp_line
			(start -0.67945 0.3048)
			(end -0.67945 -0.305054)
			(stroke
				(width 0.1)
				(type default)
			)
			(layer "F.Fab")
		)
		(fp_line
			(start -0.67945 -0.305054)
			(end -0.12065 -0.305054)
			(stroke
				(width 0.1)
				(type default)
			)
			(layer "F.Fab")
		)
		(pad "1" smd circle
			(at -0.40005 0 180)
			(size 0 0)
			(layers "F.Cu" "F.Mask" "F.Paste")
			(net "HSC_IMON")
		)
		(pad "2" smd circle
			(at 0.40005 0 180)
			(size 0 0)
			(layers "F.Cu" "F.Mask" "F.Paste")
			(net "AGND_HSC")
		)
	)
	(footprint ""
		(layer "F.Cu")
		(at 122.011948 -165.838124 180)
		(property "Reference" "R6662"
			(at 0 0 180)
			(layer "F.SilkS")
			(hide yes)
			(effects
				(font
					(size 1.27 1.27)
				)
			)
		)
		(property "Value" ""
			(at 0 0 180)
			(layer "F.Fab")
			(effects
				(font
					(size 1.27 1.27)
				)
			)
		)
		(duplicate_pad_numbers_are_jumpers no)
		(fp_line
			(start 0.7874 0.4064)
			(end -0.7874 0.4064)
			(stroke
				(width 0.1524)
				(type default)
			)
			(layer "F.SilkS")
		)
		(fp_line
			(start 0.7874 -0.4064)
			(end 0.7874 0.4064)
			(stroke
				(width 0.1524)
				(type default)
			)
			(layer "F.SilkS")
		)
		(fp_line
			(start -0.7874 0.4064)
			(end -0.7874 -0.4064)
			(stroke
				(width 0.1524)
				(type default)
			)
			(layer "F.SilkS")
		)
		(fp_line
			(start -0.7874 -0.4064)
			(end 0.7874 -0.4064)
			(stroke
				(width 0.1524)
				(type default)
			)
			(layer "F.SilkS")
		)
		(fp_line
			(start 0.67945 0.3048)
			(end 0.120396 0.3048)
			(stroke
				(width 0.1)
				(type default)
			)
			(layer "F.Fab")
		)
		(fp_line
			(start 0.67945 -0.3048)
			(end 0.67945 0.3048)
			(stroke
				(width 0.1)
				(type default)
			)
			(layer "F.Fab")
		)
		(fp_line
			(start 0.12065 -0.2794)
			(end 0.12065 -0.3048)
			(stroke
				(width 0.1)
				(type default)
			)
			(layer "F.Fab")
		)
		(fp_line
			(start 0.12065 -0.3048)
			(end 0.67945 -0.3048)
			(stroke
				(width 0.1)
				(type default)
			)
			(layer "F.Fab")
		)
		(fp_line
			(start 0.120396 0.3048)
			(end 0.120396 0.2794)
			(stroke
				(width 0.1)
				(type default)
			)
			(layer "F.Fab")
		)
		(fp_line
			(start 0.120396 0.2794)
			(end -0.12065 0.2794)
			(stroke
				(width 0.1)
				(type default)
			)
			(layer "F.Fab")
		)
		(fp_line
			(start -0.12065 0.3048)
			(end -0.67945 0.3048)
			(stroke
				(width 0.1)
				(type default)
			)
			(layer "F.Fab")
		)
		(fp_line
			(start -0.12065 0.2794)
			(end -0.12065 0.3048)
			(stroke
				(width 0.1)
				(type default)
			)
			(layer "F.Fab")
		)
		(fp_line
			(start -0.12065 -0.2794)
			(end 0.12065 -0.2794)
			(stroke
				(width 0.1)
				(type default)
			)
			(layer "F.Fab")
		)
		(fp_line
			(start -0.12065 -0.305054)
			(end -0.12065 -0.2794)
			(stroke
				(width 0.1)
				(type default)
			)
			(layer "F.Fab")
		)
		(fp_line
			(start -0.67945 0.3048)
			(end -0.67945 -0.305054)
			(stroke
				(width 0.1)
				(type default)
			)
			(layer "F.Fab")
		)
		(fp_line
			(start -0.67945 -0.305054)
			(end -0.12065 -0.305054)
			(stroke
				(width 0.1)
				(type default)
			)
			(layer "F.Fab")
		)
		(pad "1" smd circle
			(at -0.40005 0 180)
			(size 0 0)
			(layers "F.Cu" "F.Mask" "F.Paste")
			(net "NIC1_CLK_EN_BUF_N")
		)
		(pad "2" smd circle
			(at 0.40005 0 180)
			(size 0 0)
			(layers "F.Cu" "F.Mask" "F.Paste")
			(net "NIC1_CLK_EN_BUF_R_N")
		)
	)
	(footprint ""
		(layer "F.Cu")
		(at 220.36786 -53.051456)
		(property "Reference" "R4465"
			(at 0 0 0)
			(layer "F.SilkS")
			(hide yes)
			(effects
				(font
					(size 1.27 1.27)
				)
			)
		)
		(property "Value" ""
			(at 0 0 0)
			(layer "F.Fab")
			(effects
				(font
					(size 1.27 1.27)
				)
			)
		)
		(duplicate_pad_numbers_are_jumpers no)
		(fp_line
			(start -0.7874 -0.4064)
			(end 0.7874 -0.4064)
			(stroke
				(width 0.1524)
				(type default)
			)
			(layer "F.SilkS")
		)
		(fp_line
			(start -0.7874 0.4064)
			(end -0.7874 -0.4064)
			(stroke
				(width 0.1524)
				(type default)
			)
			(layer "F.SilkS")
		)
		(fp_line
			(start 0.7874 -0.4064)
			(end 0.7874 0.4064)
			(stroke
				(width 0.1524)
				(type default)
			)
			(layer "F.SilkS")
		)
		(fp_line
			(start 0.7874 0.4064)
			(end -0.7874 0.4064)
			(stroke
				(width 0.1524)
				(type default)
			)
			(layer "F.SilkS")
		)
		(fp_line
			(start -0.67945 -0.305054)
			(end -0.12065 -0.305054)
			(stroke
				(width 0.1)
				(type default)
			)
			(layer "F.Fab")
		)
		(fp_line
			(start -0.67945 0.3048)
			(end -0.67945 -0.305054)
			(stroke
				(width 0.1)
				(type default)
			)
			(layer "F.Fab")
		)
		(fp_line
			(start -0.12065 -0.305054)
			(end -0.12065 -0.2794)
			(stroke
				(width 0.1)
				(type default)
			)
			(layer "F.Fab")
		)
		(fp_line
			(start -0.12065 -0.2794)
			(end 0.12065 -0.2794)
			(stroke
				(width 0.1)
				(type default)
			)
			(layer "F.Fab")
		)
		(fp_line
			(start -0.12065 0.2794)
			(end -0.12065 0.3048)
			(stroke
				(width 0.1)
				(type default)
			)
			(layer "F.Fab")
		)
		(fp_line
			(start -0.12065 0.3048)
			(end -0.67945 0.3048)
			(stroke
				(width 0.1)
				(type default)
			)
			(layer "F.Fab")
		)
		(fp_line
			(start 0.120396 0.2794)
			(end -0.12065 0.2794)
			(stroke
				(width 0.1)
				(type default)
			)
			(layer "F.Fab")
		)
		(fp_line
			(start 0.120396 0.3048)
			(end 0.120396 0.2794)
			(stroke
				(width 0.1)
				(type default)
			)
			(layer "F.Fab")
		)
		(fp_line
			(start 0.12065 -0.3048)
			(end 0.67945 -0.3048)
			(stroke
				(width 0.1)
				(type default)
			)
			(layer "F.Fab")
		)
		(fp_line
			(start 0.12065 -0.2794)
			(end 0.12065 -0.3048)
			(stroke
				(width 0.1)
				(type default)
			)
			(layer "F.Fab")
		)
		(fp_line
			(start 0.67945 -0.3048)
			(end 0.67945 0.3048)
			(stroke
				(width 0.1)
				(type default)
			)
			(layer "F.Fab")
		)
		(fp_line
			(start 0.67945 0.3048)
			(end 0.120396 0.3048)
			(stroke
				(width 0.1)
				(type default)
			)
			(layer "F.Fab")
		)
		(pad "1" smd circle
			(at -0.40005 0)
			(size 0 0)
			(layers "F.Cu" "F.Mask" "F.Paste")
			(net "PWRGD_P12V_SSD7")
		)
		(pad "2" smd circle
			(at 0.40005 0)
			(size 0 0)
			(layers "F.Cu" "F.Mask" "F.Paste")
			(net "PWRGD_P12V_SSD7_R")
		)
	)
	(footprint ""
		(layer "F.Cu")
		(at 472.194128 -521.354304 180)
		(property "Reference" "J59_12"
			(at -2.8448 -1.402334 0)
			(unlocked yes)
			(layer "B.SilkS")
			(effects
				(font
					(size 0.7874 0.5842)
					(thickness 0.1524)
				)
				(justify mirror)
			)
		)
		(property "Value" ""
			(at 0 0 180)
			(layer "F.Fab")
			(effects
				(font
					(size 1.27 1.27)
				)
			)
		)
		(duplicate_pad_numbers_are_jumpers no)
		(pad "1" thru_hole circle
			(at 0 0 180)
			(size 0.4572 0.4572)
			(drill 0.2032)
			(layers "*.Cu" "*.Mask")
			(remove_unused_layers no)
			(net "Net_583")
			(clearance 0.127)
			(thermal_gap 0.127)
			(padstack
				(mode front_inner_back)
				(layer "Inner"
					(shape circle)
					(size 0.4572 0.4572)
					(clearance 0.127)
				)
				(layer "B.Cu"
					(shape circle)
					(size 0.508 0.508)
					(clearance 0.1016)
				)
			)
		)
	)
	(footprint ""
		(layer "F.Cu")
		(at 328.936604 -350.098614 90)
		(property "Reference" "C566"
			(at 0 0 90)
			(layer "F.SilkS")
			(hide yes)
			(effects
				(font
					(size 1.27 1.27)
				)
			)
		)
		(property "Value" ""
			(at 0 0 90)
			(layer "F.Fab")
			(effects
				(font
					(size 1.27 1.27)
				)
			)
		)
		(duplicate_pad_numbers_are_jumpers no)
		(fp_line
			(start 0.299974 -0.150114)
			(end 0.299974 0.150114)
			(stroke
				(width 0.1)
				(type default)
			)
			(layer "F.Fab")
		)
		(fp_line
			(start -0.299974 -0.150114)
			(end 0.299974 -0.150114)
			(stroke
				(width 0.1)
				(type default)
			)
			(layer "F.Fab")
		)
		(fp_line
			(start 0.299974 0.150114)
			(end -0.299974 0.150114)
			(stroke
				(width 0.1)
				(type default)
			)
			(layer "F.Fab")
		)
		(fp_line
			(start -0.299974 0.150114)
			(end -0.299974 -0.150114)
			(stroke
				(width 0.1)
				(type default)
			)
			(layer "F.Fab")
		)
		(pad "1" smd rect
			(at -0.2667 0 90)
			(size 0.3048 0.381)
			(layers "F.Cu" "F.Mask" "F.Paste")
			(net "P5E_PEX2_STN6_TX_DN<104>")
		)
		(pad "2" smd rect
			(at 0.2667 0 90)
			(size 0.3048 0.381)
			(layers "F.Cu" "F.Mask" "F.Paste")
			(net "P5E_PEX2_STN6_TX_C_DN<104>")
		)
	)
)
